#ISCELL
  mstr_misc dns *
  *
#ISCELL
  pure_quanta quanta_title_block_c *
  *
#ISCELL
  logical_power vccaux15 *
  page11_i101
#CELL
  pure_quanta q_res *
  page11_i110
#ISCELL
  standard offpage *
  page11_i115
#ISCELL
  standard offpage *
  page11_i116
#CELL
  pure_quanta q_res *
  page11_i117
#CELL
  pure_quanta q_res *
  page11_i118
#ISCELL
  standard offpage *
  page11_i124
#ISCELL
  standard offpage *
  page11_i125
#ISCELL
  standard offpage *
  page11_i126
#CELL
  pure_quanta q_res *
  page11_i128
#CELL
  pure_quanta q_res *
  page11_i129
#CELL
  pure_quanta q_res *
  page11_i130
#ISCELL
  standard offpage *
  page11_i136
#CELL
  pure_quanta q_res *
  page11_i171
#CELL
  pure_quanta q_res *
  page11_i175
#CELL
  pure_quanta q_res *
  page11_i176
#CELL
  pure_quanta q_res *
  page11_i179
#CELL
  pure_quanta q_res *
  page11_i181
#ISCELL
  standard offpage *
  page11_i193
#CELL
  pure_quanta q_res *
  page11_i194
#ISCELL
  logical_power universal_gnd *
  page11_i2
#CELL
  pure_quanta q_res *
  page11_i212
#ISCELL
  standard offpage *
  page11_i213
#CELL
  pure_quanta q_res *
  page11_i214
#ISCELL
  standard offpage *
  page11_i215
#ISCELL
  standard offpage *
  page11_i216
#ISCELL
  standard offpage *
  page11_i217
#CELL
  pure_quanta q_res *
  page11_i218
#CELL
  pure_quanta q_res *
  page11_i219
#ISCELL
  standard offpage *
  page11_i222
#CELL
  pure_quanta q_res *
  page11_i225
#ISCELL
  standard offpage *
  page11_i226
#CELL
  pure_quanta q_res *
  page11_i227
#ISCELL
  standard offpage *
  page11_i228
#ISCELL
  standard offpage *
  page11_i229
#CELL
  pure_quanta q_res *
  page11_i230
#CELL
  pure_quanta q_res *
  page11_i231
#CELL
  pure_quanta q_res *
  page11_i232
#CELL
  pure_quanta q_res *
  page11_i233
#CELL
  pure_quanta q_res *
  page11_i234
#ISCELL
  standard offpage *
  page11_i235
#ISCELL
  standard offpage *
  page11_i237
#CELL
  pure_quanta q_res *
  page11_i241
#ISCELL
  standard offpage *
  page11_i244
#CELL
  pure_quanta q_res *
  page11_i245
#ISCELL
  logical_power universal_power *
  page11_i254
#ISCELL
  standard offpage *
  page11_i255
#CELL
  pure_quanta q_res *
  page11_i256
#ISCELL
  standard offpage *
  page11_i38
#ISCELL
  standard offpage *
  page11_i42
#ISCELL
  logical_power vccaux15 *
  page11_i56
#ISCELL
  logical_power universal_gnd *
  page11_i58
#ISCELL
  standard offpage *
  page11_i63
#ISCELL
  standard offpage *
  page11_i72
#ISCELL
  standard offpage *
  page11_i76
